G04*
G04 #@! TF.GenerationSoftware,Altium Limited,Altium Designer,23.7.1 (13)*
G04*
G04 Layer_Color=32768*
%FSLAX25Y25*%
%MOIN*%
G70*
G04*
G04 #@! TF.SameCoordinates,AF00DCEB-AC48-4C7C-91EA-99F42E284231*
G04*
G04*
G04 #@! TF.FilePolarity,Positive*
G04*
G01*
G75*
%ADD23C,0.00394*%
D23*
X57422Y-125187D02*
Y-121250D01*
X55454Y-123219D02*
X59391D01*
X59588Y-108061D02*
X63525D01*
X61556Y-110029D02*
Y-106093D01*
X604109Y-2774D02*
Y1163D01*
X602141Y-805D02*
X606078D01*
X422835Y-150787D02*
Y-146850D01*
X420866Y-148819D02*
X424803D01*
X159449Y-101565D02*
X163386D01*
X161417Y-103533D02*
Y-99596D01*
X95276Y12205D02*
X99213D01*
X97244Y10236D02*
Y14173D01*
X598819Y-233071D02*
X602756D01*
X600787Y-235039D02*
Y-231102D01*
X602953Y-188076D02*
Y-184139D01*
X600984Y-186107D02*
X604921D01*
X608009Y-203853D02*
X611946D01*
X609977Y-205822D02*
Y-201885D01*
X597638Y-151969D02*
Y-148031D01*
X595669Y-150000D02*
X599606D01*
X480315Y-267717D02*
Y-263779D01*
X478346Y-265748D02*
X482283D01*
X187795Y-94488D02*
X191732D01*
X189764Y-96457D02*
Y-92520D01*
X187500Y-38976D02*
X191437D01*
X189469Y-40945D02*
Y-37008D01*
X535827Y-278740D02*
Y-274803D01*
X533858Y-276772D02*
X537795D01*
X163225Y-129469D02*
Y-123681D01*
X160331Y-126575D02*
X166119D01*
X451968Y-148031D02*
X455905D01*
X453937Y-150000D02*
Y-146063D01*
X457480Y-103937D02*
Y-100000D01*
X455512Y-101969D02*
X459449D01*
X352898Y-119882D02*
X356835D01*
X354866Y-121850D02*
Y-117913D01*
X390654Y-113958D02*
Y-110021D01*
X388685Y-111990D02*
X392622D01*
X354866Y-115157D02*
Y-111221D01*
X352898Y-113189D02*
X356835D01*
X383268Y-113779D02*
Y-109843D01*
X381299Y-111811D02*
X385236D01*
X428300Y-198819D02*
Y-194882D01*
X426332Y-196850D02*
X430269D01*
X60630Y10630D02*
Y14567D01*
X58661Y12598D02*
X62598D01*
X380583Y-146850D02*
Y-142913D01*
X378614Y-144882D02*
X382551D01*
X55472Y-52824D02*
Y-48887D01*
X53504Y-50855D02*
X57441D01*
X30709Y-20866D02*
Y-16929D01*
X28740Y-18898D02*
X32677D01*
X441339Y-117323D02*
X445276D01*
X443307Y-119291D02*
Y-115354D01*
X459938Y-127165D02*
Y-123228D01*
X457969Y-125197D02*
X461906D01*
X368898Y-113779D02*
Y-109843D01*
X366929Y-111811D02*
X370866D01*
X344488Y-153937D02*
X348425D01*
X346457Y-155905D02*
Y-151969D01*
X344449Y-133858D02*
X348386D01*
X346417Y-135827D02*
Y-131890D01*
X61417Y-18504D02*
Y-14567D01*
X59449Y-16535D02*
X63386D01*
X95669Y-79134D02*
Y-75197D01*
X93701Y-77165D02*
X97638D01*
X103543Y-51968D02*
Y-48031D01*
X101575Y-50000D02*
X105512D01*
X81112Y-63691D02*
Y-59754D01*
X79143Y-61723D02*
X83080D01*
X454528Y-78347D02*
Y-74410D01*
X452559Y-76378D02*
X456496D01*
X95276Y-94095D02*
Y-90158D01*
X93307Y-92126D02*
X97244D01*
X93307Y-99606D02*
X97244D01*
X95276Y-101575D02*
Y-97638D01*
X467717Y-76378D02*
X471654D01*
X469685Y-78347D02*
Y-74410D01*
X30709Y-11811D02*
Y-7874D01*
X28740Y-9843D02*
X32677D01*
X598819Y-220472D02*
X602756D01*
X600787Y-222441D02*
Y-218504D01*
X281890Y-197244D02*
Y-193307D01*
X279921Y-195276D02*
X283858D01*
X182516Y-125394D02*
Y-121457D01*
X180548Y-123425D02*
X184485D01*
X168110Y-103937D02*
Y-100000D01*
X166142Y-101969D02*
X170079D01*
X598819Y-226772D02*
X602756D01*
X600787Y-228740D02*
Y-224803D01*
X9843Y-239764D02*
Y-235827D01*
X7874Y-237795D02*
X11811D01*
X7087Y-351181D02*
Y-347244D01*
X5118Y-349213D02*
X9055D01*
X12205Y-298425D02*
X16142D01*
X14173Y-300394D02*
Y-296457D01*
X11811Y-195276D02*
Y-191339D01*
X9843Y-193307D02*
X13780D01*
X325590Y-241732D02*
Y-237795D01*
X323622Y-239764D02*
X327559D01*
X28740Y-3937D02*
Y0D01*
X26772Y-1969D02*
X30709D01*
X28740Y2953D02*
Y6890D01*
X26772Y4921D02*
X30709D01*
X28740Y9843D02*
Y13780D01*
X26772Y11811D02*
X30709D01*
X28740Y16732D02*
Y20669D01*
X26772Y18701D02*
X30709D01*
X146457Y-101580D02*
X150394D01*
X148425Y-103548D02*
Y-99611D01*
X151181Y-101575D02*
X155118D01*
X153150Y-103543D02*
Y-99606D01*
X610630Y-258661D02*
Y-254724D01*
X608661Y-256693D02*
X612598D01*
X613287Y-241006D02*
X617224D01*
X615256Y-242974D02*
Y-239037D01*
X602362Y-301969D02*
Y-298031D01*
X600394Y-300000D02*
X604331D01*
X614567Y-304724D02*
Y-300787D01*
X612598Y-302756D02*
X616535D01*
X598032Y-294094D02*
Y-290158D01*
X596063Y-292126D02*
X600000D01*
X610630Y-262992D02*
Y-259055D01*
X608661Y-261024D02*
X612598D01*
X339370Y-294882D02*
Y-290945D01*
X337402Y-292913D02*
X341339D01*
X320472Y-295669D02*
Y-291732D01*
X318504Y-293701D02*
X322441D01*
X563779Y-66535D02*
Y-62598D01*
X561811Y-64567D02*
X565748D01*
X603937Y-72835D02*
X607874D01*
X605905Y-74803D02*
Y-70866D01*
X131819Y-130318D02*
Y-126381D01*
X129851Y-128350D02*
X133788D01*
M02*
